# BASEBOARD_FAB2 (Tioga Pass) — schematic netlist excerpt (pin names and nets, part order shuffled) for the footprints in the layout excerpt that follows; sources: Cadence DE-HDL packaged netlist, KiCad conversion of Wiwynn_Tioga_Pass_MB.brd

C4D15  CAP_A  1.0UF 6.3V 10% X6S  pkg 0402V  page 201 : A = VR_PVCCIN_CPU0_VDD ; B = GND
R25W66  RES  100.0K 1% CHIP  pkg 0402  page 146 : A = CLK_24M_BMC_LPC ; B = GND
CF1  SC22P50V2JN-4GP  5%  pkg SMD-BCG  page 201 : \1\ = VR_PVCCIN_CPU0_AIREF1 ; \2\ = ISENSE_PVCCIN_CPU0_PH1_IMON

(kicad_pcb
	(version 20260206)
	(generator "pcbnew")
	(generator_version "10.0")
	(general
		(thickness 1.6)
		(legacy_teardrops no)
	)
	(paper "A4")
	(title_block
		(title "Wiwynn_Tioga_Pass_MB.brd")
		(comment 1 "Tioga Pass / footprints 457-459 of 4770")
	)
	(layers
		(0 "F.Cu" signal "TOP")
		(4 "In1.Cu" signal "L2GND")
		(6 "In2.Cu" signal "L3")
		(8 "In3.Cu" signal "L4GND")
		(10 "In4.Cu" signal "L5")
		(12 "In5.Cu" signal "L6GND")
		(14 "In6.Cu" signal "L7VCC")
		(16 "In7.Cu" signal "L8VCC")
		(18 "In8.Cu" signal "L9GND")
		(20 "In9.Cu" signal "L10")
		(22 "In10.Cu" signal "L11GND")
		(24 "In11.Cu" signal "L12")
		(26 "In12.Cu" signal "L13GND")
		(2 "B.Cu" signal "BOTTOM")
		(9 "F.Adhes" user "F.Adhesive")
		(11 "B.Adhes" user "B.Adhesive")
		(13 "F.Paste" user "Package Geometry/Pastemask Top")
		(15 "B.Paste" user "Package Geometry/Pastemask Bottom")
		(5 "F.SilkS" user "Ref Des/Silkscreen Top")
		(7 "B.SilkS" user "Ref Des/Silkscreen Bottom")
		(1 "F.Mask" user "Board Geometry/Soldermask Top")
		(3 "B.Mask" user "Board Geometry/Soldermask Bottom")
		(17 "Dwgs.User" user "User.Drawings")
		(19 "Cmts.User" user "User.Comments")
		(21 "Eco1.User" user "User.Eco1")
		(23 "Eco2.User" user "User.Eco2")
		(25 "Edge.Cuts" user "Board Geometry/Outline")
		(27 "Margin" user)
		(31 "F.CrtYd" user "Package Geometry/Place Bound Top")
		(29 "B.CrtYd" user "Package Geometry/Place Bound Bottom")
		(35 "F.Fab" user "Ref Des/Assembly Top")
		(33 "B.Fab" user "Ref Des/Assembly Bottom")
	)
	(footprint ""
		(layer "F.Cu")
		(at 188.98108 -65.27038 180)
		(property "Reference" "CF1"
			(at 0 0 180)
			(layer "F.SilkS")
			(hide yes)
			(effects
				(font
					(size 1.27 1.27)
				)
			)
		)
		(property "Value" "*"
			(at 1.1811 -2.8194 180)
			(unlocked yes)
			(layer "F.Fab")
			(hide yes)
			(effects
				(font
					(size 1.27 1.016)
					(thickness 0.1524)
				)
			)
		)
		(property "Device Type" "SC22P50V2JN-4GP_SMD-BCG-SC22P5A"
			(at 1.1811 -4.3434 180)
			(unlocked yes)
			(layer "F.Fab")
			(hide yes)
			(effects
				(font
					(size 1.27 1.016)
					(thickness 0.1524)
				)
			)
		)
		(duplicate_pad_numbers_are_jumpers no)
		(fp_rect
			(start -0.4318 0.9525)
			(end 0.4318 -0.9525)
			(stroke
				(width 0)
				(type default)
			)
			(fill no)
			(layer "F.CrtYd")
		)
		(fp_rect
			(start -0.4318 0.9525)
			(end 0.4318 -0.9525)
			(stroke
				(width 0)
				(type default)
			)
			(fill no)
			(layer "F.Fab")
		)
		(pad "1" smd custom
			(at 0 -0.4445 180)
			(size 0.1524 0.1524)
			(layers "F.Cu" "F.Mask" "F.Paste")
			(net "VR_PVCCIN_CPU0_AIREF1")
			(options
				(clearance outline)
				(anchor circle)
			)
			(primitives
				(gr_poly
					(pts
						(arc
							(start 0.3048 -0.2032)
							(mid 0.275042 -0.275042)
							(end 0.2032 -0.3048)
						)
						(arc
							(start -0.2032 -0.3048)
							(mid -0.275042 -0.275042)
							(end -0.3048 -0.2032)
						)
						(arc
							(start -0.3048 0.2032)
							(mid -0.275042 0.275042)
							(end -0.2032 0.3048)
						)
						(arc
							(start 0.2032 0.3048)
							(mid 0.275042 0.275042)
							(end 0.3048 0.2032)
						)
					)
					(width 0)
					(fill yes)
				)
			)
		)
		(pad "2" smd custom
			(at 0 0.4445 180)
			(size 0.1524 0.1524)
			(layers "F.Cu" "F.Mask" "F.Paste")
			(net "ISENSE_PVCCIN_CPU0_PH1_IMON")
			(options
				(clearance outline)
				(anchor circle)
			)
			(primitives
				(gr_poly
					(pts
						(arc
							(start 0.3048 -0.2032)
							(mid 0.275042 -0.275042)
							(end 0.2032 -0.3048)
						)
						(arc
							(start -0.2032 -0.3048)
							(mid -0.275042 -0.275042)
							(end -0.3048 -0.2032)
						)
						(arc
							(start -0.3048 0.2032)
							(mid -0.275042 0.275042)
							(end -0.2032 0.3048)
						)
						(arc
							(start 0.2032 0.3048)
							(mid 0.275042 0.275042)
							(end 0.3048 0.2032)
						)
					)
					(width 0)
					(fill yes)
				)
			)
		)
	)
	(footprint ""
		(layer "F.Cu")
		(at 181.1147 -76.52385 -90)
		(property "Reference" "C4D15"
			(at 0 0 270)
			(layer "F.SilkS")
			(hide yes)
			(effects
				(font
					(size 1.27 1.27)
				)
			)
		)
		(property "Value" ""
			(at 0 0 270)
			(layer "F.Fab")
			(effects
				(font
					(size 1.27 1.27)
				)
			)
		)
		(duplicate_pad_numbers_are_jumpers no)
		(fp_poly
			(pts
				(xy 0.3048 -0.1016) (xy 0.3048 0.9906) (xy -0.3048 0.9906) (xy -0.3048 -0.1016)
			)
			(stroke
				(width 0)
				(type default)
			)
			(fill no)
			(layer "F.CrtYd")
		)
		(fp_line
			(start -0.3048 0.9906)
			(end 0.3048 0.9906)
			(stroke
				(width 0.1)
				(type default)
			)
			(layer "F.Fab")
		)
		(fp_line
			(start 0.3048 0.9906)
			(end 0.3048 -0.1016)
			(stroke
				(width 0.1)
				(type default)
			)
			(layer "F.Fab")
		)
		(fp_line
			(start -0.3048 -0.1016)
			(end -0.3048 0.9906)
			(stroke
				(width 0.1)
				(type default)
			)
			(layer "F.Fab")
		)
		(fp_line
			(start 0.3048 -0.1016)
			(end -0.3048 -0.1016)
			(stroke
				(width 0.1)
				(type default)
			)
			(layer "F.Fab")
		)
		(pad "1" smd rect
			(at 0 0 270)
			(size 0.508 0.508)
			(layers "F.Cu" "F.Mask" "F.Paste")
			(net "VR_PVCCIN_CPU0_VDD")
		)
		(pad "2" smd rect
			(at 0 0.889 270)
			(size 0.508 0.508)
			(layers "F.Cu" "F.Mask" "F.Paste")
			(net "GND")
		)
		(zone
			(layer "F.Cu")
			(hatch none 0.5)
			(connect_pads
				(clearance 0)
			)
			(min_thickness 0.25)
			(keepout
				(tracks not_allowed)
				(vias allowed)
				(pads allowed)
				(copperpour not_allowed)
				(footprints allowed)
			)
			(placement
				(enabled no)
				(sheetname "")
			)
			(fill
				(thermal_gap 0.5)
				(thermal_bridge_width 0.5)
				(island_removal_mode 0)
			)
			(polygon
				(pts
					(xy 180.4797 -76.77785) (xy 180.4797 -76.26985) (xy 180.8607 -76.26985) (xy 180.8607 -76.77785)
				)
			)
		)
		(zone
			(layer "F.Cu")
			(hatch none 0.5)
			(connect_pads
				(clearance 0)
			)
			(min_thickness 0.25)
			(keepout
				(tracks allowed)
				(vias not_allowed)
				(pads allowed)
				(copperpour not_allowed)
				(footprints allowed)
			)
			(placement
				(enabled no)
				(sheetname "")
			)
			(fill
				(thermal_gap 0.5)
				(thermal_bridge_width 0.5)
				(island_removal_mode 0)
			)
			(polygon
				(pts
					(xy 180.8607 -76.77785) (xy 180.8607 -76.26985) (xy 180.4797 -76.26985) (xy 180.4797 -76.77785)
				)
			)
		)
	)
	(footprint ""
		(layer "F.Cu")
		(at 407.399236 -47.889414 180)
		(property "Reference" "R25W66"
			(at -0.8382 -0.67818 180)
			(unlocked yes)
			(layer "F.SilkS")
			(effects
				(font
					(size 0.4064 0.254)
					(thickness 0.1524)
				)
				(justify left)
			)
		)
		(property "Value" ""
			(at 0 0 180)
			(layer "F.Fab")
			(effects
				(font
					(size 1.27 1.27)
				)
			)
		)
		(duplicate_pad_numbers_are_jumpers no)
		(fp_poly
			(pts
				(xy -0.2794 -0.1016) (xy 0.2794 -0.1016) (xy 0.2794 0.9906) (xy -0.2794 0.9906)
			)
			(stroke
				(width 0)
				(type default)
			)
			(fill no)
			(layer "F.CrtYd")
		)
		(fp_line
			(start 0.2794 0.9906)
			(end 0.2794 -0.1016)
			(stroke
				(width 0.1)
				(type default)
			)
			(layer "F.Fab")
		)
		(fp_line
			(start 0.2794 -0.1016)
			(end -0.2794 -0.1016)
			(stroke
				(width 0.1)
				(type default)
			)
			(layer "F.Fab")
		)
		(fp_line
			(start -0.2794 0.9906)
			(end 0.2794 0.9906)
			(stroke
				(width 0.1)
				(type default)
			)
			(layer "F.Fab")
		)
		(fp_line
			(start -0.2794 -0.1016)
			(end -0.2794 0.9906)
			(stroke
				(width 0.1)
				(type default)
			)
			(layer "F.Fab")
		)
		(pad "1" smd rect
			(at 0 0 180)
			(size 0.508 0.508)
			(layers "F.Cu" "F.Mask" "F.Paste")
			(net "CLK_24M_BMC_LPC")
		)
		(pad "2" smd rect
			(at 0 0.889 180)
			(size 0.508 0.508)
			(layers "F.Cu" "F.Mask" "F.Paste")
			(net "GND")
		)
		(zone
			(layer "F.Cu")
			(hatch none 0.5)
			(connect_pads
				(clearance 0)
			)
			(min_thickness 0.25)
			(keepout
				(tracks not_allowed)
				(vias allowed)
				(pads allowed)
				(copperpour not_allowed)
				(footprints allowed)
			)
			(placement
				(enabled no)
				(sheetname "")
			)
			(fill
				(thermal_gap 0.5)
				(thermal_bridge_width 0.5)
				(island_removal_mode 0)
			)
			(polygon
				(pts
					(xy 407.653236 -48.524414) (xy 407.145236 -48.524414) (xy 407.145236 -48.143414) (xy 407.653236 -48.143414)
				)
			)
		)
		(zone
			(layer "F.Cu")
			(hatch none 0.5)
			(connect_pads
				(clearance 0)
			)
			(min_thickness 0.25)
			(keepout
				(tracks allowed)
				(vias not_allowed)
				(pads allowed)
				(copperpour not_allowed)
				(footprints allowed)
			)
			(placement
				(enabled no)
				(sheetname "")
			)
			(fill
				(thermal_gap 0.5)
				(thermal_bridge_width 0.5)
				(island_removal_mode 0)
			)
			(polygon
				(pts
					(xy 407.653236 -48.143414) (xy 407.145236 -48.143414) (xy 407.145236 -48.524414) (xy 407.653236 -48.524414)
				)
			)
		)
	)
)
